FILE_TYPE = MACRO_DRAWING;
SET COLOR_WIRE YELLOW;
SET COLOR_PROP ORANGE;
SET COLOR_DOT WHITE;
SET COLOR_ARC YELLOW;
SET COLOR_BODY GREEN;
SET COLOR_NOTE PURPLE;
SET PROP_DISPLAY VALUE;
SET PAGE_NUMBER P180;
FORCEADD UNIVERSAL_GND..1
(4500 -825);
FORCEPROP 3 LASTPIN (4500 -775) SIG_NAME GND\g
J 0
(4510 -765);
DISPLAY 0.659574 (4510 -765);
PAINT MONO (4510 -765);
DISPLAY INVISIBLE (4510 -765);
FORCEPROP 2 LAST CDS_LIB logical_power
J 0
(4500 -825);
PAINT MONO (4500 -825);
DISPLAY INVISIBLE (4500 -825);
FORCEPROP 1 LAST HDL_POWER GND
J 1
(4525 -900);
DISPLAY 0.872340 (4525 -900);
PAINT GREEN (4525 -900);
DISPLAY INVISIBLE (4525 -900);
FORCEPROP 1 LAST PATH I10
J 0
(4575 -825);
DISPLAY 0.872340 (4575 -825);
PAINT AQUA (4575 -825);
DISPLAY INVISIBLE (4575 -825);
FORCEPROP 2 LAST ROOM IO_SLOT
J 1
(4275 -750);
DISPLAY 0.744681 (4275 -750);
DISPLAY INVISIBLE (4275 -750);
FORCEADD UNIVERSAL_GND..1
(-1200 -825);
FORCEPROP 3 LASTPIN (-1200 -775) SIG_NAME GND\g
J 0
(-1190 -765);
DISPLAY 0.659574 (-1190 -765);
PAINT MONO (-1190 -765);
DISPLAY INVISIBLE (-1190 -765);
FORCEPROP 2 LAST CDS_LIB logical_power
J 0
(-1200 -825);
PAINT MONO (-1200 -825);
DISPLAY INVISIBLE (-1200 -825);
FORCEPROP 1 LAST HDL_POWER GND
J 1
(-1175 -900);
DISPLAY 0.872340 (-1175 -900);
PAINT GREEN (-1175 -900);
DISPLAY INVISIBLE (-1175 -900);
FORCEPROP 1 LAST PATH I2
J 0
(-1125 -825);
DISPLAY 0.872340 (-1125 -825);
PAINT AQUA (-1125 -825);
DISPLAY INVISIBLE (-1125 -825);
FORCEPROP 2 LAST ROOM IO_SLOT
J 1
(-1425 -750);
DISPLAY 0.744681 (-1425 -750);
DISPLAY INVISIBLE (-1425 -750);
FORCEADD UNIVERSAL_GND..1
(2100 -825);
FORCEPROP 3 LASTPIN (2100 -775) SIG_NAME GND\g
J 0
(2110 -765);
DISPLAY 0.659574 (2110 -765);
PAINT MONO (2110 -765);
DISPLAY INVISIBLE (2110 -765);
FORCEPROP 2 LAST CDS_LIB logical_power
J 0
(2100 -825);
PAINT MONO (2100 -825);
DISPLAY INVISIBLE (2100 -825);
FORCEPROP 1 LAST HDL_POWER GND
J 1
(2125 -900);
DISPLAY 0.872340 (2125 -900);
PAINT GREEN (2125 -900);
DISPLAY INVISIBLE (2125 -900);
FORCEPROP 1 LAST PATH I5
J 0
(2175 -825);
DISPLAY 0.872340 (2175 -825);
PAINT AQUA (2175 -825);
DISPLAY INVISIBLE (2175 -825);
FORCEPROP 2 LAST ROOM IO_SLOT
J 1
(1875 -750);
DISPLAY 0.744681 (1875 -750);
DISPLAY INVISIBLE (1875 -750);
FORCEADD EMMITSBURG_REV0P9..10
(-300 1450);
FORCEPROP 1 LAST PART_NUMBER AJ0QV2N0T00
J 0
(-801 3470);
DISPLAY 0.723404 (-801 3470);
PAINT GREEN (-801 3470);
DISPLAY INVISIBLE (-801 3470);
FORCEPROP 2 LAST PART_TYPE SMLF
J 0
(-800 3725);
DISPLAY 1.021277 (-800 3725);
FORCEPROP 2 LAST VALUE GFNOCPU04302300-QV2N-MM#99A1WT
J 0
(-800 3675);
DISPLAY 1.021277 (-800 3675);
FORCEPROP 1 LAST MATERIAL IC
J 0
(-801 3343);
DISPLAY 0.723404 (-801 3343);
PAINT GREEN (-801 3343);
FORCEPROP 1 LAST $LOCATION U4
J 0
(-801 3617);
DISPLAY 0.723404 (-801 3617);
PAINT GREEN (-801 3617);
FORCEPROP 2 LASTPIN (350 -225) $PN AY3
J 0
(360 -215);
DISPLAY 0.808511 (360 -215);
FORCEPROP 2 LASTPIN (350 25) $PN AY5
J 0
(360 35);
DISPLAY 0.808511 (360 35);
FORCEPROP 2 LASTPIN (350 75) $PN AY8
J 0
(360 85);
DISPLAY 0.808511 (360 85);
FORCEPROP 2 LASTPIN (350 -275) $PN AY28
J 0
(360 -265);
DISPLAY 0.808511 (360 -265);
FORCEPROP 2 LASTPIN (350 -175) $PN AY31
J 0
(360 -165);
DISPLAY 0.808511 (360 -165);
FORCEPROP 2 LASTPIN (350 -125) $PN AY34
J 0
(360 -115);
DISPLAY 0.808511 (360 -115);
FORCEPROP 2 LASTPIN (350 -75) $PN AY37
J 0
(360 -65);
DISPLAY 0.808511 (360 -65);
FORCEPROP 2 LASTPIN (350 -25) $PN AY39
J 0
(360 -15);
DISPLAY 0.808511 (360 -15);
FORCEPROP 2 LASTPIN (350 275) $PN B9
J 0
(360 285);
DISPLAY 0.808511 (360 285);
FORCEPROP 2 LASTPIN (350 125) $PN B13
J 0
(360 135);
DISPLAY 0.808511 (360 135);
FORCEPROP 2 LASTPIN (350 175) $PN B29
J 0
(360 185);
DISPLAY 0.808511 (360 185);
FORCEPROP 2 LASTPIN (350 225) $PN B39
J 0
(360 235);
DISPLAY 0.808511 (360 235);
FORCEPROP 2 LASTPIN (350 375) $PN BB5
J 0
(360 385);
DISPLAY 0.808511 (360 385);
FORCEPROP 2 LASTPIN (350 325) $PN BB39
J 0
(360 335);
DISPLAY 0.808511 (360 335);
FORCEPROP 2 LASTPIN (350 1175) $PN BC6
J 0
(360 1185);
DISPLAY 0.808511 (360 1185);
FORCEPROP 2 LASTPIN (350 1225) $PN BC8
J 0
(360 1235);
DISPLAY 0.808511 (360 1235);
FORCEPROP 2 LASTPIN (350 425) $PN BC10
J 0
(360 435);
DISPLAY 0.808511 (360 435);
FORCEPROP 2 LASTPIN (350 475) $PN BC12
J 0
(360 485);
DISPLAY 0.808511 (360 485);
FORCEPROP 2 LASTPIN (350 575) $PN BC16
J 0
(360 585);
DISPLAY 0.808511 (360 585);
FORCEPROP 2 LASTPIN (350 625) $PN BC18
J 0
(360 635);
DISPLAY 0.808511 (360 635);
FORCEPROP 2 LASTPIN (350 675) $PN BC20
J 0
(360 685);
DISPLAY 0.808511 (360 685);
FORCEPROP 2 LASTPIN (350 725) $PN BC22
J 0
(360 735);
DISPLAY 0.808511 (360 735);
FORCEPROP 2 LASTPIN (350 775) $PN BC24
J 0
(360 785);
DISPLAY 0.808511 (360 785);
FORCEPROP 2 LASTPIN (350 825) $PN BC26
J 0
(360 835);
DISPLAY 0.808511 (360 835);
FORCEPROP 2 LASTPIN (350 875) $PN BC28
J 0
(360 885);
DISPLAY 0.808511 (360 885);
FORCEPROP 2 LASTPIN (350 925) $PN BC30
J 0
(360 935);
DISPLAY 0.808511 (360 935);
FORCEPROP 2 LASTPIN (350 975) $PN BC32
J 0
(360 985);
DISPLAY 0.808511 (360 985);
FORCEPROP 2 LASTPIN (350 1025) $PN BC34
J 0
(360 1035);
DISPLAY 0.808511 (360 1035);
FORCEPROP 2 LASTPIN (350 1075) $PN BC36
J 0
(360 1085);
DISPLAY 0.808511 (360 1085);
FORCEPROP 2 LASTPIN (350 1125) $PN BC38
J 0
(360 1135);
DISPLAY 0.808511 (360 1135);
FORCEPROP 2 LASTPIN (350 1375) $PN BD5
J 0
(360 1385);
DISPLAY 0.808511 (360 1385);
FORCEPROP 2 LASTPIN (350 1275) $PN BD21
J 0
(360 1285);
DISPLAY 0.808511 (360 1285);
FORCEPROP 2 LASTPIN (350 1325) $PN BD39
J 0
(360 1335);
DISPLAY 0.808511 (360 1335);
FORCEPROP 2 LASTPIN (350 1425) $PN BE10
J 0
(360 1435);
DISPLAY 0.808511 (360 1435);
FORCEPROP 2 LASTPIN (350 1475) $PN BE34
J 0
(360 1485);
DISPLAY 0.808511 (360 1485);
FORCEPROP 2 LASTPIN (350 1525) $PN BF21
J 0
(360 1535);
DISPLAY 0.808511 (360 1535);
FORCEPROP 2 LASTPIN (350 1575) $PN BG10
J 0
(360 1585);
DISPLAY 0.808511 (360 1585);
FORCEPROP 2 LASTPIN (350 1625) $PN BG34
J 0
(360 1635);
DISPLAY 0.808511 (360 1635);
FORCEPROP 2 LASTPIN (350 1925) $PN C4
J 0
(360 1935);
DISPLAY 0.808511 (360 1935);
FORCEPROP 2 LASTPIN (350 1675) $PN C20
J 0
(360 1685);
DISPLAY 0.808511 (360 1685);
FORCEPROP 2 LASTPIN (350 1725) $PN C22
J 0
(360 1735);
DISPLAY 0.808511 (360 1735);
FORCEPROP 2 LASTPIN (350 1775) $PN C24
J 0
(360 1785);
DISPLAY 0.808511 (360 1785);
FORCEPROP 2 LASTPIN (350 1825) $PN C26
J 0
(360 1835);
DISPLAY 0.808511 (360 1835);
FORCEPROP 2 LASTPIN (350 1875) $PN C38
J 0
(360 1885);
DISPLAY 0.808511 (360 1885);
FORCEPROP 2 LASTPIN (350 2075) $PN D5
J 0
(360 2085);
DISPLAY 0.808511 (360 2085);
FORCEPROP 2 LASTPIN (350 2125) $PN D9
J 0
(360 2135);
DISPLAY 0.808511 (360 2135);
FORCEPROP 2 LASTPIN (350 1975) $PN D13
J 0
(360 1985);
DISPLAY 0.808511 (360 1985);
FORCEPROP 2 LASTPIN (350 2025) $PN D29
J 0
(360 2035);
DISPLAY 0.808511 (360 2035);
FORCEPROP 2 LASTPIN (350 2975) $PN E6
J 0
(360 2985);
DISPLAY 0.808511 (360 2985);
FORCEPROP 2 LASTPIN (350 3025) $PN E8
J 0
(360 3035);
DISPLAY 0.808511 (360 3035);
FORCEPROP 2 LASTPIN (350 2175) $PN E10
J 0
(360 2185);
DISPLAY 0.808511 (360 2185);
FORCEPROP 2 LASTPIN (350 2225) $PN E12
J 0
(360 2235);
DISPLAY 0.808511 (360 2235);
FORCEPROP 2 LASTPIN (350 2275) $PN E14
J 0
(360 2285);
DISPLAY 0.808511 (360 2285);
FORCEPROP 2 LASTPIN (350 2325) $PN E16
J 0
(360 2335);
DISPLAY 0.808511 (360 2335);
FORCEPROP 2 LASTPIN (350 2375) $PN E18
J 0
(360 2385);
DISPLAY 0.808511 (360 2385);
FORCEPROP 2 LASTPIN (350 2425) $PN E20
J 0
(360 2435);
DISPLAY 0.808511 (360 2435);
FORCEPROP 2 LASTPIN (350 2475) $PN E22
J 0
(360 2485);
DISPLAY 0.808511 (360 2485);
FORCEPROP 2 LASTPIN (350 2525) $PN E24
J 0
(360 2535);
DISPLAY 0.808511 (360 2535);
FORCEPROP 2 LASTPIN (350 2575) $PN E26
J 0
(360 2585);
DISPLAY 0.808511 (360 2585);
FORCEPROP 2 LASTPIN (350 2625) $PN E28
J 0
(360 2635);
DISPLAY 0.808511 (360 2635);
FORCEPROP 2 LASTPIN (350 2675) $PN E30
J 0
(360 2685);
DISPLAY 0.808511 (360 2685);
FORCEPROP 2 LASTPIN (350 2725) $PN E32
J 0
(360 2735);
DISPLAY 0.808511 (360 2735);
FORCEPROP 2 LASTPIN (350 2775) $PN E34
J 0
(360 2785);
DISPLAY 0.808511 (360 2785);
FORCEPROP 2 LASTPIN (350 2825) $PN E36
J 0
(360 2835);
DISPLAY 0.808511 (360 2835);
FORCEPROP 2 LASTPIN (350 2875) $PN E38
J 0
(360 2885);
DISPLAY 0.808511 (360 2885);
FORCEPROP 2 LASTPIN (350 2925) $PN E40
J 0
(360 2935);
DISPLAY 0.808511 (360 2935);
FORCEPROP 2 LASTPIN (350 3075) $PN F15
J 0
(360 3085);
DISPLAY 0.808511 (360 3085);
FORCEPROP 2 LASTPIN (350 3125) $PN F24
J 0
(360 3135);
DISPLAY 0.808511 (360 3135);
FORCEPROP 2 LASTPIN (350 3175) $PN F31
J 0
(360 3185);
DISPLAY 0.808511 (360 3185);
FORCEPROP 2 LASTPIN (-950 -275) $PN F34
J 2
(-960 -265);
DISPLAY 0.808511 (-960 -265);
FORCEPROP 2 LASTPIN (-950 -225) $PN F39
J 2
(-960 -215);
DISPLAY 0.808511 (-960 -215);
FORCEPROP 2 LASTPIN (-950 -175) $PN F41
J 2
(-960 -165);
DISPLAY 0.808511 (-960 -165);
FORCEPROP 2 LASTPIN (-950 -125) $PN G13
J 2
(-960 -115);
DISPLAY 0.808511 (-960 -115);
FORCEPROP 2 LASTPIN (-950 -75) $PN G20
J 2
(-960 -65);
DISPLAY 0.808511 (-960 -65);
FORCEPROP 2 LASTPIN (-950 -25) $PN G26
J 2
(-960 -15);
DISPLAY 0.808511 (-960 -15);
FORCEPROP 2 LASTPIN (-950 75) $PN H5
J 2
(-960 85);
DISPLAY 0.808511 (-960 85);
FORCEPROP 2 LASTPIN (-950 125) $PN H8
J 2
(-960 135);
DISPLAY 0.808511 (-960 135);
FORCEPROP 2 LASTPIN (-950 25) $PN H39
J 2
(-960 35);
DISPLAY 0.808511 (-960 35);
FORCEPROP 2 LASTPIN (-950 175) $PN J13
J 2
(-960 185);
DISPLAY 0.808511 (-960 185);
FORCEPROP 2 LASTPIN (-950 225) $PN J20
J 2
(-960 235);
DISPLAY 0.808511 (-960 235);
FORCEPROP 2 LASTPIN (-950 275) $PN J26
J 2
(-960 285);
DISPLAY 0.808511 (-960 285);
FORCEPROP 2 LASTPIN (-950 575) $PN K5
J 2
(-960 585);
DISPLAY 0.808511 (-960 585);
FORCEPROP 2 LASTPIN (-950 325) $PN K11
J 2
(-960 335);
DISPLAY 0.808511 (-960 335);
FORCEPROP 2 LASTPIN (-950 375) $PN K15
J 2
(-960 385);
DISPLAY 0.808511 (-960 385);
FORCEPROP 2 LASTPIN (-950 425) $PN K24
J 2
(-960 435);
DISPLAY 0.808511 (-960 435);
FORCEPROP 2 LASTPIN (-950 475) $PN K34
J 2
(-960 485);
DISPLAY 0.808511 (-960 485);
FORCEPROP 2 LASTPIN (-950 525) $PN K39
J 2
(-960 535);
DISPLAY 0.808511 (-960 535);
FORCEPROP 2 LASTPIN (-950 625) $PN L10
J 2
(-960 635);
DISPLAY 0.808511 (-960 635);
FORCEPROP 2 LASTPIN (-950 675) $PN L16
J 2
(-960 685);
DISPLAY 0.808511 (-960 685);
FORCEPROP 2 LASTPIN (-950 725) $PN L20
J 2
(-960 735);
DISPLAY 0.808511 (-960 735);
FORCEPROP 2 LASTPIN (-950 775) $PN L23
J 2
(-960 785);
DISPLAY 0.808511 (-960 785);
FORCEPROP 2 LASTPIN (-950 825) $PN L26
J 2
(-960 835);
DISPLAY 0.808511 (-960 835);
FORCEPROP 2 LASTPIN (-950 875) $PN L29
J 2
(-960 885);
DISPLAY 0.808511 (-960 885);
FORCEPROP 2 LASTPIN (-950 925) $PN L36
J 2
(-960 935);
DISPLAY 0.808511 (-960 935);
FORCEPROP 2 LASTPIN (-950 975) $PN M1
J 2
(-960 985);
DISPLAY 0.808511 (-960 985);
FORCEPROP 2 LASTPIN (-950 1275) $PN M3
J 2
(-960 1285);
DISPLAY 0.808511 (-960 1285);
FORCEPROP 2 LASTPIN (-950 1525) $PN M5
J 2
(-960 1535);
DISPLAY 0.808511 (-960 1535);
FORCEPROP 2 LASTPIN (-950 1025) $PN M11
J 2
(-960 1035);
DISPLAY 0.808511 (-960 1035);
FORCEPROP 2 LASTPIN (-950 1075) $PN M15
J 2
(-960 1085);
DISPLAY 0.808511 (-960 1085);
FORCEPROP 2 LASTPIN (-950 1125) $PN M18
J 2
(-960 1135);
DISPLAY 0.808511 (-960 1135);
FORCEPROP 2 LASTPIN (-950 1175) $PN M21
J 2
(-960 1185);
DISPLAY 0.808511 (-960 1185);
FORCEPROP 2 LASTPIN (-950 1225) $PN M28
J 2
(-960 1235);
DISPLAY 0.808511 (-960 1235);
FORCEPROP 2 LASTPIN (-950 1325) $PN M31
J 2
(-960 1335);
DISPLAY 0.808511 (-960 1335);
FORCEPROP 2 LASTPIN (-950 1375) $PN M34
J 2
(-960 1385);
DISPLAY 0.808511 (-960 1385);
FORCEPROP 2 LASTPIN (-950 1425) $PN M37
J 2
(-960 1435);
DISPLAY 0.808511 (-960 1435);
FORCEPROP 2 LASTPIN (-950 1475) $PN M39
J 2
(-960 1485);
DISPLAY 0.808511 (-960 1485);
FORCEPROP 2 LASTPIN (-950 1575) $PN N16
J 2
(-960 1585);
DISPLAY 0.808511 (-960 1585);
FORCEPROP 2 LASTPIN (-950 1625) $PN N32
J 2
(-960 1635);
DISPLAY 0.808511 (-960 1635);
FORCEPROP 2 LASTPIN (-950 2075) $PN P5
J 2
(-960 2085);
DISPLAY 0.808511 (-960 2085);
FORCEPROP 2 LASTPIN (-950 2125) $PN P8
J 2
(-960 2135);
DISPLAY 0.808511 (-960 2135);
FORCEPROP 2 LASTPIN (-950 1675) $PN P11
J 2
(-960 1685);
DISPLAY 0.808511 (-960 1685);
FORCEPROP 2 LASTPIN (-950 1725) $PN P24
J 2
(-960 1735);
DISPLAY 0.808511 (-960 1735);
FORCEPROP 2 LASTPIN (-950 1775) $PN P28
J 2
(-960 1785);
DISPLAY 0.808511 (-960 1785);
FORCEPROP 2 LASTPIN (-950 1825) $PN P31
J 2
(-960 1835);
DISPLAY 0.808511 (-960 1835);
FORCEPROP 2 LASTPIN (-950 1875) $PN P37
J 2
(-960 1885);
DISPLAY 0.808511 (-960 1885);
FORCEPROP 2 LASTPIN (-950 1925) $PN P39
J 2
(-960 1935);
DISPLAY 0.808511 (-960 1935);
FORCEPROP 2 LASTPIN (-950 1975) $PN P41
J 2
(-960 1985);
DISPLAY 0.808511 (-960 1985);
FORCEPROP 2 LASTPIN (-950 2025) $PN P43
J 2
(-960 2035);
DISPLAY 0.808511 (-960 2035);
FORCEPROP 2 LASTPIN (-950 2175) $PN R13
J 2
(-960 2185);
DISPLAY 0.808511 (-960 2185);
FORCEPROP 2 LASTPIN (-950 2225) $PN R16
J 2
(-960 2235);
DISPLAY 0.808511 (-960 2235);
FORCEPROP 2 LASTPIN (-950 2275) $PN R20
J 2
(-960 2285);
DISPLAY 0.808511 (-960 2285);
FORCEPROP 2 LASTPIN (-950 2325) $PN R36
J 2
(-960 2335);
DISPLAY 0.808511 (-960 2335);
FORCEPROP 2 LASTPIN (-950 2375) $PN T31
J 2
(-960 2385);
DISPLAY 0.808511 (-960 2385);
FORCEPROP 2 LASTPIN (-950 2625) $PN U5
J 2
(-960 2635);
DISPLAY 0.808511 (-960 2635);
FORCEPROP 2 LASTPIN (-950 2425) $PN U10
J 2
(-960 2435);
DISPLAY 0.808511 (-960 2435);
FORCEPROP 2 LASTPIN (-950 2475) $PN U13
J 2
(-960 2485);
DISPLAY 0.808511 (-960 2485);
FORCEPROP 2 LASTPIN (-950 2525) $PN U25
J 2
(-960 2535);
DISPLAY 0.808511 (-960 2535);
FORCEPROP 2 LASTPIN (-950 2575) $PN U39
J 2
(-960 2585);
DISPLAY 0.808511 (-960 2585);
FORCEPROP 2 LASTPIN (-950 2675) $PN V2
J 2
(-960 2685);
DISPLAY 0.808511 (-960 2685);
FORCEPROP 2 LASTPIN (-950 2725) $PN V31
J 2
(-960 2735);
DISPLAY 0.808511 (-960 2735);
FORCEPROP 2 LASTPIN (-950 2825) $PN W3
J 2
(-960 2835);
DISPLAY 0.808511 (-960 2835);
FORCEPROP 2 LASTPIN (-950 2925) $PN W5
J 2
(-960 2935);
DISPLAY 0.808511 (-960 2935);
FORCEPROP 2 LASTPIN (-950 2775) $PN W25
J 2
(-960 2785);
DISPLAY 0.808511 (-960 2785);
FORCEPROP 2 LASTPIN (-950 2875) $PN W39
J 2
(-960 2885);
DISPLAY 0.808511 (-960 2885);
FORCEPROP 2 LASTPIN (-950 3175) $PN Y8
J 2
(-960 3185);
DISPLAY 0.808511 (-960 3185);
FORCEPROP 2 LASTPIN (-950 2975) $PN Y11
J 2
(-960 2985);
DISPLAY 0.808511 (-960 2985);
FORCEPROP 2 LASTPIN (-950 3025) $PN Y15
J 2
(-960 3035);
DISPLAY 0.808511 (-960 3035);
FORCEPROP 2 LASTPIN (-950 3075) $PN Y31
J 2
(-960 3085);
DISPLAY 0.808511 (-960 3085);
FORCEPROP 2 LASTPIN (-950 3125) $PN Y34
J 2
(-960 3135);
DISPLAY 0.808511 (-960 3135);
FORCEPROP 2 LASTPIN (350 525) $PN BC14
J 0
(360 535);
DISPLAY 0.808511 (360 535);
FORCEPROP 2 LAST CDS_LIB pure_quanta
J 0
(-300 1450);
PAINT MONO (-300 1450);
DISPLAY INVISIBLE (-300 1450);
FORCEPROP 1 LAST CDS_LMAN_SYM_OUTLINE -500,1875,500,-1875
J 0
(-300 1450);
DISPLAY 0.468085 (-300 1450);
PAINT GREEN (-300 1450);
DISPLAY INVISIBLE (-300 1450);
FORCEPROP 1 LAST NEEDS_NO_SIZE TRUE
J 0
(-300 1450);
DISPLAY 0.723404 (-300 1450);
PAINT GREEN (-300 1450);
DISPLAY INVISIBLE (-300 1450);
FORCEPROP 1 LAST PATH I7
J 0
(-300 1450);
DISPLAY 0.723404 (-300 1450);
PAINT GREEN (-300 1450);
DISPLAY INVISIBLE (-300 1450);
FORCEPROP 2 LAST CDS_LOCATION U4
J 0
(-800 3500);
DISPLAY 1.021277 (-800 3500);
DISPLAY INVISIBLE (-800 3500);
FORCEPROP 2 LAST $SEC 10
J 0
(-800 3775);
DISPLAY 0.680851 (-800 3775);
PAINT MONO (-800 3775);
DISPLAY INVISIBLE (-800 3775);
FORCEPROP 2 LAST CDS_SEC 10
J 0
(-800 3500);
DISPLAY 1.021277 (-800 3500);
DISPLAY INVISIBLE (-800 3500);
FORCEADD UNIVERSAL_GND..1
(600 -825);
FORCEPROP 3 LASTPIN (600 -775) SIG_NAME GND\g
J 0
(610 -765);
DISPLAY 0.659574 (610 -765);
PAINT MONO (610 -765);
DISPLAY INVISIBLE (610 -765);
FORCEPROP 2 LAST CDS_LIB logical_power
J 0
(600 -825);
PAINT MONO (600 -825);
DISPLAY INVISIBLE (600 -825);
FORCEPROP 1 LAST HDL_POWER GND
J 1
(625 -900);
DISPLAY 0.872340 (625 -900);
PAINT GREEN (625 -900);
DISPLAY INVISIBLE (625 -900);
FORCEPROP 1 LAST PATH I8
J 0
(675 -825);
DISPLAY 0.872340 (675 -825);
PAINT AQUA (675 -825);
DISPLAY INVISIBLE (675 -825);
FORCEPROP 2 LAST ROOM IO_SLOT
J 1
(375 -750);
DISPLAY 0.744681 (375 -750);
DISPLAY INVISIBLE (375 -750);
FORCEADD EMMITSBURG_REV0P9..11
(3300 1500);
FORCEPROP 1 LAST PART_NUMBER AJ0QV2N0T00
J 0
(2511 3472);
DISPLAY 0.723404 (2511 3472);
PAINT GREEN (2511 3472);
DISPLAY INVISIBLE (2511 3472);
FORCEPROP 1 LAST MATERIAL IC
J 0
(2511 3345);
DISPLAY 0.723404 (2511 3345);
PAINT GREEN (2511 3345);
FORCEPROP 2 LAST VALUE GFNOCPU04302300-QV2N-MM#99A1WT
J 0
(2525 3675);
DISPLAY 1.021277 (2525 3675);
FORCEPROP 2 LAST PART_TYPE SMLF
J 0
(2525 3725);
DISPLAY 1.021277 (2525 3725);
FORCEPROP 1 LAST $LOCATION U4
J 0
(2511 3619);
DISPLAY 0.723404 (2511 3619);
PAINT GREEN (2511 3619);
FORCEPROP 2 LASTPIN (4250 -75) $PN A6
J 0
(4260 -65);
DISPLAY 0.808511 (4260 -65);
FORCEPROP 2 LASTPIN (4250 1375) $PN A20
J 0
(4260 1385);
DISPLAY 0.808511 (4260 1385);
FORCEPROP 2 LASTPIN (4250 1425) $PN A22
J 0
(4260 1435);
DISPLAY 0.808511 (4260 1435);
FORCEPROP 2 LASTPIN (4250 1475) $PN A24
J 0
(4260 1485);
DISPLAY 0.808511 (4260 1485);
FORCEPROP 2 LASTPIN (4250 1525) $PN A26
J 0
(4260 1535);
DISPLAY 0.808511 (4260 1535);
FORCEPROP 2 LASTPIN (4250 -175) $PN A38
J 0
(4260 -165);
DISPLAY 0.808511 (4260 -165);
FORCEPROP 2 LASTPIN (4250 -125) $PN A40
J 0
(4260 -115);
DISPLAY 0.808511 (4260 -115);
FORCEPROP 2 LASTPIN (4250 2075) $PN AA5
J 0
(4260 2085);
DISPLAY 0.808511 (4260 2085);
FORCEPROP 2 LASTPIN (4250 1575) $PN AA17
J 0
(4260 1585);
DISPLAY 0.808511 (4260 1585);
FORCEPROP 2 LASTPIN (4250 1625) $PN AA19
J 0
(4260 1635);
DISPLAY 0.808511 (4260 1635);
FORCEPROP 2 LASTPIN (4250 1675) $PN AA20
J 0
(4260 1685);
DISPLAY 0.808511 (4260 1685);
FORCEPROP 2 LASTPIN (4250 1725) $PN AA22
J 0
(4260 1735);
DISPLAY 0.808511 (4260 1735);
FORCEPROP 2 LASTPIN (4250 1775) $PN AA24
J 0
(4260 1785);
DISPLAY 0.808511 (4260 1785);
FORCEPROP 2 LASTPIN (4250 1825) $PN AA25
J 0
(4260 1835);
DISPLAY 0.808511 (4260 1835);
FORCEPROP 2 LASTPIN (4250 1875) $PN AA27
J 0
(4260 1885);
DISPLAY 0.808511 (4260 1885);
FORCEPROP 2 LASTPIN (4250 1925) $PN AA32
J 0
(4260 1935);
DISPLAY 0.808511 (4260 1935);
FORCEPROP 2 LASTPIN (4250 1975) $PN AA36
J 0
(4260 1985);
DISPLAY 0.808511 (4260 1985);
FORCEPROP 2 LASTPIN (4250 2025) $PN AA39
J 0
(4260 2035);
DISPLAY 0.808511 (4260 2035);
FORCEPROP 2 LASTPIN (4250 2125) $PN AB15
J 0
(4260 2135);
DISPLAY 0.808511 (4260 2135);
FORCEPROP 2 LASTPIN (4250 2175) $PN AB17
J 0
(4260 2185);
DISPLAY 0.808511 (4260 2185);
FORCEPROP 2 LASTPIN (4250 2225) $PN AB25
J 0
(4260 2235);
DISPLAY 0.808511 (4260 2235);
FORCEPROP 2 LASTPIN (4250 2275) $PN AB37
J 0
(4260 2285);
DISPLAY 0.808511 (4260 2285);
FORCEPROP 2 LASTPIN (4250 2525) $PN AC5
J 0
(4260 2535);
DISPLAY 0.808511 (4260 2535);
FORCEPROP 2 LASTPIN (4250 2325) $PN AC29
J 0
(4260 2335);
DISPLAY 0.808511 (4260 2335);
FORCEPROP 2 LASTPIN (4250 2375) $PN AC32
J 0
(4260 2385);
DISPLAY 0.808511 (4260 2385);
FORCEPROP 2 LASTPIN (4250 2425) $PN AC36
J 0
(4260 2435);
DISPLAY 0.808511 (4260 2435);
FORCEPROP 2 LASTPIN (4250 2475) $PN AC39
J 0
(4260 2485);
DISPLAY 0.808511 (4260 2485);
FORCEPROP 2 LASTPIN (4250 2925) $PN AD8
J 0
(4260 2935);
DISPLAY 0.808511 (4260 2935);
FORCEPROP 2 LASTPIN (4250 2575) $PN AD11
J 0
(4260 2585);
DISPLAY 0.808511 (4260 2585);
FORCEPROP 2 LASTPIN (4250 2625) $PN AD19
J 0
(4260 2635);
DISPLAY 0.808511 (4260 2635);
FORCEPROP 2 LASTPIN (4250 2675) $PN AD20
J 0
(4260 2685);
DISPLAY 0.808511 (4260 2685);
FORCEPROP 2 LASTPIN (4250 2725) $PN AD22
J 0
(4260 2735);
DISPLAY 0.808511 (4260 2735);
FORCEPROP 2 LASTPIN (4250 2775) $PN AD24
J 0
(4260 2785);
DISPLAY 0.808511 (4260 2785);
FORCEPROP 2 LASTPIN (4250 2825) $PN AD31
J 0
(4260 2835);
DISPLAY 0.808511 (4260 2835);
FORCEPROP 2 LASTPIN (4250 2875) $PN AD34
J 0
(4260 2885);
DISPLAY 0.808511 (4260 2885);
FORCEPROP 2 LASTPIN (4250 3075) $PN AE5
J 0
(4260 3085);
DISPLAY 0.808511 (4260 3085);
FORCEPROP 2 LASTPIN (4250 2975) $PN AE13
J 0
(4260 2985);
DISPLAY 0.808511 (4260 2985);
FORCEPROP 2 LASTPIN (4250 3025) $PN AE39
J 0
(4260 3035);
DISPLAY 0.808511 (4260 3035);
FORCEPROP 2 LASTPIN (4250 3125) $PN AF19
J 0
(4260 3135);
DISPLAY 0.808511 (4260 3135);
FORCEPROP 2 LASTPIN (4250 3175) $PN AF24
J 0
(4260 3185);
DISPLAY 0.808511 (4260 3185);
FORCEPROP 2 LASTPIN (2350 -125) $PN AF31
J 2
(2340 -115);
DISPLAY 0.808511 (2340 -115);
FORCEPROP 2 LASTPIN (2350 -75) $PN AF40
J 2
(2340 -65);
DISPLAY 0.808511 (2340 -65);
FORCEPROP 2 LASTPIN (2350 -25) $PN AF42
J 2
(2340 -15);
DISPLAY 0.808511 (2340 -15);
FORCEPROP 2 LASTPIN (2350 225) $PN AG5
J 2
(2340 235);
DISPLAY 0.808511 (2340 235);
FORCEPROP 2 LASTPIN (2350 25) $PN AG13
J 2
(2340 35);
DISPLAY 0.808511 (2340 35);
FORCEPROP 2 LASTPIN (2350 75) $PN AG19
J 2
(2340 85);
DISPLAY 0.808511 (2340 85);
FORCEPROP 2 LASTPIN (2350 125) $PN AG24
J 2
(2340 135);
DISPLAY 0.808511 (2340 135);
FORCEPROP 2 LASTPIN (2350 175) $PN AG39
J 2
(2340 185);
DISPLAY 0.808511 (2340 185);
FORCEPROP 2 LASTPIN (2350 325) $PN AH8
J 2
(2340 335);
DISPLAY 0.808511 (2340 335);
FORCEPROP 2 LASTPIN (2350 275) $PN AH31
J 2
(2340 285);
DISPLAY 0.808511 (2340 285);
FORCEPROP 2 LASTPIN (2350 625) $PN AJ5
J 2
(2340 635);
DISPLAY 0.808511 (2340 635);
FORCEPROP 2 LASTPIN (2350 375) $PN AJ19
J 2
(2340 385);
DISPLAY 0.808511 (2340 385);
FORCEPROP 2 LASTPIN (2350 425) $PN AJ24
J 2
(2340 435);
DISPLAY 0.808511 (2340 435);
FORCEPROP 2 LASTPIN (2350 475) $PN AJ29
J 2
(2340 485);
DISPLAY 0.808511 (2340 485);
FORCEPROP 2 LASTPIN (2350 525) $PN AJ36
J 2
(2340 535);
DISPLAY 0.808511 (2340 535);
FORCEPROP 2 LASTPIN (2350 575) $PN AJ39
J 2
(2340 585);
DISPLAY 0.808511 (2340 585);
FORCEPROP 2 LASTPIN (2350 725) $PN AK2
J 2
(2340 735);
DISPLAY 0.808511 (2340 735);
FORCEPROP 2 LASTPIN (2350 825) $PN AK4
J 2
(2340 835);
DISPLAY 0.808511 (2340 835);
FORCEPROP 2 LASTPIN (2350 675) $PN AK11
J 2
(2340 685);
DISPLAY 0.808511 (2340 685);
FORCEPROP 2 LASTPIN (2350 775) $PN AK37
J 2
(2340 785);
DISPLAY 0.808511 (2340 785);
FORCEPROP 2 LASTPIN (2350 875) $PN AL19
J 2
(2340 885);
DISPLAY 0.808511 (2340 885);
FORCEPROP 2 LASTPIN (2350 925) $PN AL24
J 2
(2340 935);
DISPLAY 0.808511 (2340 935);
FORCEPROP 2 LASTPIN (2350 975) $PN AL27
J 2
(2340 985);
DISPLAY 0.808511 (2340 985);
FORCEPROP 2 LASTPIN (2350 1025) $PN AL29
J 2
(2340 1035);
DISPLAY 0.808511 (2340 1035);
FORCEPROP 2 LASTPIN (2350 1075) $PN AL39
J 2
(2340 1085);
DISPLAY 0.808511 (2340 1085);
FORCEPROP 2 LASTPIN (2350 1225) $PN AM8
J 2
(2340 1235);
DISPLAY 0.808511 (2340 1235);
FORCEPROP 2 LASTPIN (2350 1125) $PN AM15
J 2
(2340 1135);
DISPLAY 0.808511 (2340 1135);
FORCEPROP 2 LASTPIN (2350 1175) $PN AM31
J 2
(2340 1185);
DISPLAY 0.808511 (2340 1185);
FORCEPROP 2 LASTPIN (2350 1275) $PN AN13
J 2
(2340 1285);
DISPLAY 0.808511 (2340 1285);
FORCEPROP 2 LASTPIN (2350 1325) $PN AN16
J 2
(2340 1335);
DISPLAY 0.808511 (2340 1335);
FORCEPROP 2 LASTPIN (2350 1375) $PN AN29
J 2
(2340 1385);
DISPLAY 0.808511 (2340 1385);
FORCEPROP 2 LASTPIN (2350 1425) $PN AN32
J 2
(2340 1435);
DISPLAY 0.808511 (2340 1435);
FORCEPROP 2 LASTPIN (2350 1775) $PN AP5
J 2
(2340 1785);
DISPLAY 0.808511 (2340 1785);
FORCEPROP 2 LASTPIN (2350 1475) $PN AP11
J 2
(2340 1485);
DISPLAY 0.808511 (2340 1485);
FORCEPROP 2 LASTPIN (2350 1525) $PN AP18
J 2
(2340 1535);
DISPLAY 0.808511 (2340 1535);
FORCEPROP 2 LASTPIN (2350 1575) $PN AP24
J 2
(2340 1585);
DISPLAY 0.808511 (2340 1585);
FORCEPROP 2 LASTPIN (2350 1625) $PN AP28
J 2
(2340 1635);
DISPLAY 0.808511 (2340 1635);
FORCEPROP 2 LASTPIN (2350 1675) $PN AP37
J 2
(2340 1685);
DISPLAY 0.808511 (2340 1685);
FORCEPROP 2 LASTPIN (2350 1725) $PN AP39
J 2
(2340 1735);
DISPLAY 0.808511 (2340 1735);
FORCEPROP 2 LASTPIN (2350 1825) $PN AR20
J 2
(2340 1835);
DISPLAY 0.808511 (2340 1835);
FORCEPROP 2 LASTPIN (2350 1875) $PN AR32
J 2
(2340 1885);
DISPLAY 0.808511 (2340 1885);
FORCEPROP 2 LASTPIN (2350 2325) $PN AT5
J 2
(2340 2335);
DISPLAY 0.808511 (2340 2335);
FORCEPROP 2 LASTPIN (2350 2375) $PN AT8
J 2
(2340 2385);
DISPLAY 0.808511 (2340 2385);
FORCEPROP 2 LASTPIN (2350 1925) $PN AT11
J 2
(2340 1935);
DISPLAY 0.808511 (2340 1935);
FORCEPROP 2 LASTPIN (2350 1975) $PN AT15
J 2
(2340 1985);
DISPLAY 0.808511 (2340 1985);
FORCEPROP 2 LASTPIN (2350 2025) $PN AT21
J 2
(2340 2035);
DISPLAY 0.808511 (2340 2035);
FORCEPROP 2 LASTPIN (2350 2075) $PN AT24
J 2
(2340 2085);
DISPLAY 0.808511 (2340 2085);
FORCEPROP 2 LASTPIN (2350 2125) $PN AT28
J 2
(2340 2135);
DISPLAY 0.808511 (2340 2135);
FORCEPROP 2 LASTPIN (2350 2175) $PN AT31
J 2
(2340 2185);
DISPLAY 0.808511 (2340 2185);
FORCEPROP 2 LASTPIN (2350 2225) $PN AT34
J 2
(2340 2235);
DISPLAY 0.808511 (2340 2235);
FORCEPROP 2 LASTPIN (2350 2275) $PN AT39
J 2
(2340 2285);
DISPLAY 0.808511 (2340 2285);
FORCEPROP 2 LASTPIN (2350 2425) $PN AU20
J 2
(2340 2435);
DISPLAY 0.808511 (2340 2435);
FORCEPROP 2 LASTPIN (2350 2475) $PN AU23
J 2
(2340 2485);
DISPLAY 0.808511 (2340 2485);
FORCEPROP 2 LASTPIN (2350 2525) $PN AU26
J 2
(2340 2535);
DISPLAY 0.808511 (2340 2535);
FORCEPROP 2 LASTPIN (2350 2575) $PN AU29
J 2
(2340 2585);
DISPLAY 0.808511 (2340 2585);
FORCEPROP 2 LASTPIN (2350 2625) $PN AU32
J 2
(2340 2635);
DISPLAY 0.808511 (2340 2635);
FORCEPROP 2 LASTPIN (2350 2675) $PN AU36
J 2
(2340 2685);
DISPLAY 0.808511 (2340 2685);
FORCEPROP 2 LASTPIN (2350 2825) $PN AV5
J 2
(2340 2835);
DISPLAY 0.808511 (2340 2835);
FORCEPROP 2 LASTPIN (2350 2875) $PN AV8
J 2
(2340 2885);
DISPLAY 0.808511 (2340 2885);
FORCEPROP 2 LASTPIN (2350 2725) $PN AV37
J 2
(2340 2735);
DISPLAY 0.808511 (2340 2735);
FORCEPROP 2 LASTPIN (2350 2775) $PN AV39
J 2
(2340 2785);
DISPLAY 0.808511 (2340 2785);
FORCEPROP 2 LASTPIN (2350 2925) $PN AW7
J 2
(2340 2935);
DISPLAY 0.808511 (2340 2935);
FORCEPROP 2 LASTPIN (2350 2975) $PN AY11
J 2
(2340 2985);
DISPLAY 0.808511 (2340 2985);
FORCEPROP 2 LASTPIN (2350 3025) $PN AY15
J 2
(2340 3035);
DISPLAY 0.808511 (2340 3035);
FORCEPROP 2 LASTPIN (2350 3075) $PN AY18
J 2
(2340 3085);
DISPLAY 0.808511 (2340 3085);
FORCEPROP 2 LASTPIN (2350 3125) $PN AY21
J 2
(2340 3135);
DISPLAY 0.808511 (2340 3135);
FORCEPROP 2 LASTPIN (2350 3175) $PN AY24
J 2
(2340 3185);
DISPLAY 0.808511 (2340 3185);
FORCEPROP 2 LASTPIN (4250 -25) $PN BB1
J 0
(4260 -15);
DISPLAY 0.808511 (4260 -15);
FORCEPROP 2 LASTPIN (4250 925) $PN BC2
J 0
(4260 935);
DISPLAY 0.808511 (4260 935);
FORCEPROP 2 LASTPIN (4250 975) $PN BC42
J 0
(4260 985);
DISPLAY 0.808511 (4260 985);
FORCEPROP 2 LASTPIN (4250 275) $PN BD1
J 0
(4260 285);
DISPLAY 0.808511 (4260 285);
FORCEPROP 2 LASTPIN (4250 1025) $PN BD3
J 0
(4260 1035);
DISPLAY 0.808511 (4260 1035);
FORCEPROP 2 LASTPIN (4250 1075) $PN BD41
J 0
(4260 1085);
DISPLAY 0.808511 (4260 1085);
FORCEPROP 2 LASTPIN (4250 325) $PN BD43
J 0
(4260 335);
DISPLAY 0.808511 (4260 335);
FORCEPROP 2 LASTPIN (4250 375) $PN BE1
J 0
(4260 385);
DISPLAY 0.808511 (4260 385);
FORCEPROP 2 LASTPIN (4250 425) $PN BE3
J 0
(4260 435);
DISPLAY 0.808511 (4260 435);
FORCEPROP 2 LASTPIN (4250 475) $PN BE41
J 0
(4260 485);
DISPLAY 0.808511 (4260 485);
FORCEPROP 2 LASTPIN (4250 525) $PN BE43
J 0
(4260 535);
DISPLAY 0.808511 (4260 535);
FORCEPROP 2 LASTPIN (4250 75) $PN BG4
J 0
(4260 85);
DISPLAY 0.808511 (4260 85);
FORCEPROP 2 LASTPIN (4250 125) $PN BG6
J 0
(4260 135);
DISPLAY 0.808511 (4260 135);
FORCEPROP 2 LASTPIN (4250 25) $PN BG38
J 0
(4260 35);
DISPLAY 0.808511 (4260 35);
FORCEPROP 2 LASTPIN (4250 575) $PN BG41
J 0
(4260 585);
DISPLAY 0.808511 (4260 585);
FORCEPROP 2 LASTPIN (4250 625) $PN C3
J 0
(4260 635);
DISPLAY 0.808511 (4260 635);
FORCEPROP 2 LASTPIN (4250 675) $PN C41
J 0
(4260 685);
DISPLAY 0.808511 (4260 685);
FORCEPROP 2 LASTPIN (4250 725) $PN C43
J 0
(4260 735);
DISPLAY 0.808511 (4260 735);
FORCEPROP 2 LASTPIN (4250 775) $PN D1
J 0
(4260 785);
DISPLAY 0.808511 (4260 785);
FORCEPROP 2 LASTPIN (4250 1125) $PN D3
J 0
(4260 1135);
DISPLAY 0.808511 (4260 1135);
FORCEPROP 2 LASTPIN (4250 1175) $PN D41
J 0
(4260 1185);
DISPLAY 0.808511 (4260 1185);
FORCEPROP 2 LASTPIN (4250 825) $PN D43
J 0
(4260 835);
DISPLAY 0.808511 (4260 835);
FORCEPROP 2 LASTPIN (4250 1225) $PN E2
J 0
(4260 1235);
DISPLAY 0.808511 (4260 1235);
FORCEPROP 2 LASTPIN (4250 1275) $PN E42
J 0
(4260 1285);
DISPLAY 0.808511 (4260 1285);
FORCEPROP 2 LASTPIN (4250 175) $PN F43
J 0
(4260 185);
DISPLAY 0.808511 (4260 185);
FORCEPROP 2 LAST CDS_LIB pure_quanta
J 0
(3300 1500);
PAINT MONO (3300 1500);
DISPLAY INVISIBLE (3300 1500);
FORCEPROP 1 LAST CDS_LMAN_SYM_OUTLINE -800,1825,800,-1825
J 0
(3300 1500);
DISPLAY 0.468085 (3300 1500);
PAINT GREEN (3300 1500);
DISPLAY INVISIBLE (3300 1500);
FORCEPROP 1 LAST NEEDS_NO_SIZE TRUE
J 0
(3300 1500);
DISPLAY 0.723404 (3300 1500);
PAINT GREEN (3300 1500);
DISPLAY INVISIBLE (3300 1500);
FORCEPROP 1 LAST PATH I9
J 0
(3300 1500);
DISPLAY 0.723404 (3300 1500);
PAINT GREEN (3300 1500);
DISPLAY INVISIBLE (3300 1500);
FORCEPROP 2 LAST CDS_LOCATION U4
J 0
(2500 3500);
DISPLAY 1.021277 (2500 3500);
DISPLAY INVISIBLE (2500 3500);
FORCEPROP 2 LAST $SEC 11
J 0
(2525 3775);
DISPLAY 0.680851 (2525 3775);
PAINT MONO (2525 3775);
DISPLAY INVISIBLE (2525 3775);
FORCEPROP 2 LAST CDS_SEC 11
J 0
(2500 3500);
DISPLAY 1.021277 (2500 3500);
DISPLAY INVISIBLE (2500 3500);
FORCEADD QUANTA_TITLE_BLOCK_C..1
(6200 -2125);
FORCEPROP 0 LAST CDS_CON_LAST_MODIFIED Fri Aug 25 14:03:00 2023
J 0
(4315 -2110);
PAINT MONO (4315 -2110);
DISPLAY INVISIBLE (4315 -2110);
FORCEPROP 2 LAST CUSTOM_TXT_CDS <XR_PAGE_TITLE>
J 0
(-1690 3125);
DISPLAY 0.638298 (-1690 3125);
PAINT PINK (-1690 3125);
DISPLAY INVISIBLE (-1690 3125);
FORCEPROP 2 LAST CUSTOM_TXT_CDS <CON_PAGE_NUM> OF <CON_TOTAL_PAGES>
J 0
(5725 -2125);
DISPLAY 0.978723 (5725 -2125);
FORCEPROP 2 LAST CUSTOM_TXT_CDS <Q_REV>
J 0
(6016 -2022);
DISPLAY 1.212766 (6016 -2022);
FORCEPROP 2 LAST CUSTOM_TXT_CDS <CON_LAST_MODIFIED>
J 0
(4315 -2110);
DISPLAY 0.978723 (4315 -2110);
FORCEPROP 2 LAST CUSTOM_TXT_CDS <Q_NUMBER>
J 0
(4797 -2022);
DISPLAY 1.212766 (4797 -2022);
FORCEPROP 2 LAST CUSTOM_TXT_CDS <Q_PROJ>
J 0
(3900 -1975);
DISPLAY 1.212766 (3900 -1975);
FORCEPROP 1 LAST CUSTOM_TXT_CDS <NAME_2>
J 0
(3025 -2075);
FORCEPROP 1 LAST CUSTOM_TXT_CDS <NAME_1>
J 0
(3025 -1950);
FORCEPROP 1 LAST Q_TITLE EMMITSBURG - GND (10/10)
J 0
(-3116 -2099);
DISPLAY 1.957447 (-3116 -2099);
PAINT GREEN (-3116 -2099);
FORCEPROP 1 LAST Q_DEPT 
J 1
(2437 -2076);
DISPLAY 1.957447 (2437 -2076);
PAINT GREEN (2437 -2076);
FORCEPROP 2 LAST CDS_XR_PAGE_TITLE CR-188 : @S9S_MB_2U_LIB.S9S_MB_2U(SCH_1):PAGE188
J 0
(-1690 3125);
DISPLAY 0.638298 (-1690 3125);
PAINT PINK (-1690 3125);
DISPLAY INVISIBLE (-1690 3125);
FORCEPROP 1 LAST COMMENT_BODY TRUE
J 0
(6212 -2138);
DISPLAY 0.978723 (6212 -2138);
PAINT GREEN (6212 -2138);
DISPLAY INVISIBLE (6212 -2138);
FORCEPROP 2 LAST PAGE_BORDER TRUE
J 0
(-1690 3125);
DISPLAY 0.638298 (-1690 3125);
PAINT PINK (-1690 3125);
DISPLAY INVISIBLE (-1690 3125);
FORCEPROP 1 LAST CDS_LMAN_SYM_OUTLINE -9475,6775,100,-125
J 0
(6200 -2125);
DISPLAY 0.468085 (6200 -2125);
PAINT GREEN (6200 -2125);
DISPLAY INVISIBLE (6200 -2125);
FORCEPROP 2 LAST CDS_LIB pure_quanta
J 0
(6200 -2125);
PAINT MONO (6200 -2125);
DISPLAY INVISIBLE (6200 -2125);
WIRE 16 -1 (600 -275)(600 -775);
WIRE 16 -1 (600 -225)(600 -275);
WIRE 16 -1 (350 -275)(600 -275);
WIRE 16 -1 (2100 -125)(2100 -775);
WIRE 16 -1 (2100 -75)(2100 -125);
WIRE 16 -1 (2100 -125)(2350 -125);
WIRE 16 -1 (-1200 -275)(-1200 -775);
WIRE 16 -1 (-1200 -225)(-1200 -275);
WIRE 16 -1 (-1200 -275)(-950 -275);
WIRE 16 -1 (4500 -175)(4500 -775);
WIRE 16 -1 (4500 -175)(4500 -125);
WIRE 16 -1 (4250 -175)(4500 -175);
WIRE 16 -1 (2100 3175)(2350 3175);
WIRE 16 -1 (2100 3175)(2100 3125);
WIRE 16 -1 (2100 3125)(2350 3125);
WIRE 16 -1 (2100 3125)(2100 3075);
WIRE 16 -1 (2100 3075)(2350 3075);
WIRE 16 -1 (2100 3025)(2350 3025);
WIRE 16 -1 (2100 3075)(2100 3025);
WIRE 16 -1 (2100 3025)(2100 2975);
WIRE 16 -1 (2350 2975)(2100 2975);
WIRE 16 -1 (2100 2975)(2100 2925);
WIRE 16 -1 (2100 2925)(2350 2925);
WIRE 16 -1 (2100 2925)(2100 2875);
WIRE 16 -1 (2100 2875)(2350 2875);
WIRE 16 -1 (2100 2875)(2100 2825);
WIRE 16 -1 (2100 2825)(2350 2825);
WIRE 16 -1 (2100 2825)(2100 2775);
WIRE 16 -1 (2100 2775)(2350 2775);
WIRE 16 -1 (2100 2775)(2100 2725);
WIRE 16 -1 (2350 2725)(2100 2725);
WIRE 16 -1 (2100 2725)(2100 2675);
WIRE 16 -1 (2100 2675)(2350 2675);
WIRE 16 -1 (2100 2675)(2100 2625);
WIRE 16 -1 (2100 2625)(2350 2625);
WIRE 16 -1 (2100 2625)(2100 2575);
WIRE 16 -1 (2100 2575)(2350 2575);
WIRE 16 -1 (2100 2525)(2350 2525);
WIRE 16 -1 (2100 2575)(2100 2525);
WIRE 16 -1 (2100 2525)(2100 2475);
WIRE 16 -1 (2100 2475)(2350 2475);
WIRE 16 -1 (2100 2475)(2100 2425);
WIRE 16 -1 (2350 2425)(2100 2425);
WIRE 16 -1 (2100 2425)(2100 2375);
WIRE 16 -1 (2100 2375)(2350 2375);
WIRE 16 -1 (2100 2375)(2100 2325);
WIRE 16 -1 (2100 2325)(2350 2325);
WIRE 16 -1 (2100 2325)(2100 2275);
WIRE 16 -1 (2100 2275)(2350 2275);
WIRE 16 -1 (2100 2275)(2100 2225);
WIRE 16 -1 (2100 2225)(2350 2225);
WIRE 16 -1 (2100 2225)(2100 2175);
WIRE 16 -1 (2100 2175)(2350 2175);
WIRE 16 -1 (2100 2175)(2100 2125);
WIRE 16 -1 (2100 2125)(2350 2125);
WIRE 16 -1 (2100 2125)(2100 2075);
WIRE 16 -1 (2350 2075)(2100 2075);
WIRE 16 -1 (2100 2025)(2350 2025);
WIRE 16 -1 (2100 2075)(2100 2025);
WIRE 16 -1 (2100 2025)(2100 1975);
WIRE 16 -1 (2100 1975)(2350 1975);
WIRE 16 -1 (2100 1975)(2100 1925);
WIRE 16 -1 (2100 1925)(2350 1925);
WIRE 16 -1 (2100 1925)(2100 1875);
WIRE 16 -1 (2100 1875)(2350 1875);
WIRE 16 -1 (2100 1875)(2100 1825);
WIRE 16 -1 (2100 1825)(2350 1825);
WIRE 16 -1 (2100 1825)(2100 1775);
WIRE 16 -1 (2100 1775)(2350 1775);
WIRE 16 -1 (2100 1775)(2100 1725);
WIRE 16 -1 (2100 1725)(2350 1725);
WIRE 16 -1 (2100 1725)(2100 1675);
WIRE 16 -1 (2350 1675)(2100 1675);
WIRE 16 -1 (2100 1675)(2100 1625);
WIRE 16 -1 (2100 1625)(2350 1625);
WIRE 16 -1 (2100 1625)(2100 1575);
WIRE 16 -1 (2100 1575)(2350 1575);
WIRE 16 -1 (2100 1525)(2350 1525);
WIRE 16 -1 (2100 1575)(2100 1525);
WIRE 16 -1 (2100 1525)(2100 1475);
WIRE 16 -1 (2100 1475)(2350 1475);
WIRE 16 -1 (2100 1475)(2100 1425);
WIRE 16 -1 (2100 1425)(2350 1425);
WIRE 16 -1 (2100 1425)(2100 1375);
WIRE 16 -1 (2350 1375)(2100 1375);
WIRE 16 -1 (2100 1375)(2100 1325);
WIRE 16 -1 (2100 1325)(2350 1325);
WIRE 16 -1 (2100 1325)(2100 1275);
WIRE 16 -1 (2100 1275)(2350 1275);
WIRE 16 -1 (2100 1275)(2100 1225);
WIRE 16 -1 (2100 1225)(2350 1225);
WIRE 16 -1 (2100 1225)(2100 1175);
WIRE 16 -1 (2100 1175)(2350 1175);
WIRE 16 -1 (2100 1175)(2100 1125);
WIRE 16 -1 (2100 1125)(2350 1125);
WIRE 16 -1 (2100 1125)(2100 1075);
WIRE 16 -1 (2100 1075)(2350 1075);
WIRE 16 -1 (2100 1075)(2100 1025);
WIRE 16 -1 (2350 1025)(2100 1025);
WIRE 16 -1 (2100 975)(2350 975);
WIRE 16 -1 (2100 1025)(2100 975);
WIRE 16 -1 (2100 975)(2100 925);
WIRE 16 -1 (2100 925)(2350 925);
WIRE 16 -1 (2100 925)(2100 875);
WIRE 16 -1 (2100 875)(2350 875);
WIRE 16 -1 (2100 875)(2100 825);
WIRE 16 -1 (2100 825)(2350 825);
WIRE 16 -1 (2100 825)(2100 775);
WIRE 16 -1 (2100 775)(2350 775);
WIRE 16 -1 (2100 775)(2100 725);
WIRE 16 -1 (2100 725)(2350 725);
WIRE 16 -1 (2100 725)(2100 675);
WIRE 16 -1 (2100 675)(2350 675);
WIRE 16 -1 (2100 675)(2100 625);
WIRE 16 -1 (2350 625)(2100 625);
WIRE 16 -1 (2100 625)(2100 575);
WIRE 16 -1 (2100 575)(2350 575);
WIRE 16 -1 (2100 575)(2100 525);
WIRE 16 -1 (2100 525)(2350 525);
WIRE 16 -1 (2100 475)(2350 475);
WIRE 16 -1 (2100 525)(2100 475);
WIRE 16 -1 (2100 475)(2100 425);
WIRE 16 -1 (2100 425)(2350 425);
WIRE 16 -1 (2100 425)(2100 375);
WIRE 16 -1 (2100 375)(2350 375);
WIRE 16 -1 (2100 375)(2100 325);
WIRE 16 -1 (2350 325)(2100 325);
WIRE 16 -1 (2100 325)(2100 275);
WIRE 16 -1 (2100 275)(2350 275);
WIRE 16 -1 (2100 275)(2100 225);
WIRE 16 -1 (2100 225)(2350 225);
WIRE 16 -1 (2100 225)(2100 175);
WIRE 16 -1 (2100 175)(2350 175);
WIRE 16 -1 (2100 175)(2100 125);
WIRE 16 -1 (2100 125)(2350 125);
WIRE 16 -1 (2100 125)(2100 75);
WIRE 16 -1 (2100 75)(2350 75);
WIRE 16 -1 (2100 75)(2100 25);
WIRE 16 -1 (2100 25)(2350 25);
WIRE 16 -1 (2350 -25)(2100 -25);
WIRE 16 -1 (2100 25)(2100 -25);
WIRE 16 -1 (2100 -25)(2100 -75);
WIRE 16 -1 (2100 -75)(2350 -75);
WIRE 16 -1 (350 3175)(600 3175);
WIRE 16 -1 (350 3125)(600 3125);
WIRE 16 -1 (600 3175)(600 3125);
WIRE 16 -1 (350 3075)(600 3075);
WIRE 16 -1 (600 3125)(600 3075);
WIRE 16 -1 (350 3025)(600 3025);
WIRE 16 -1 (600 3025)(600 3075);
WIRE 16 -1 (350 2975)(600 2975);
WIRE 16 -1 (600 3025)(600 2975);
WIRE 16 -1 (600 2925)(350 2925);
WIRE 16 -1 (600 2975)(600 2925);
WIRE 16 -1 (350 2875)(600 2875);
WIRE 16 -1 (600 2925)(600 2875);
WIRE 16 -1 (350 2825)(600 2825);
WIRE 16 -1 (600 2875)(600 2825);
WIRE 16 -1 (350 2775)(600 2775);
WIRE 16 -1 (600 2825)(600 2775);
WIRE 16 -1 (350 2725)(600 2725);
WIRE 16 -1 (600 2725)(600 2775);
WIRE 16 -1 (350 2675)(600 2675);
WIRE 16 -1 (600 2725)(600 2675);
WIRE 16 -1 (600 2625)(350 2625);
WIRE 16 -1 (600 2675)(600 2625);
WIRE 16 -1 (600 2575)(350 2575);
WIRE 16 -1 (600 2625)(600 2575);
WIRE 16 -1 (600 2525)(350 2525);
WIRE 16 -1 (600 2575)(600 2525);
WIRE 16 -1 (600 2475)(350 2475);
WIRE 16 -1 (600 2525)(600 2475);
WIRE 16 -1 (350 2425)(600 2425);
WIRE 16 -1 (600 2425)(600 2475);
WIRE 16 -1 (600 2375)(350 2375);
WIRE 16 -1 (600 2375)(600 2425);
WIRE 16 -1 (600 2325)(350 2325);
WIRE 16 -1 (600 2375)(600 2325);
WIRE 16 -1 (600 2275)(350 2275);
WIRE 16 -1 (600 2325)(600 2275);
WIRE 16 -1 (350 2225)(600 2225);
WIRE 16 -1 (600 2275)(600 2225);
WIRE 16 -1 (350 2175)(600 2175);
WIRE 16 -1 (600 2225)(600 2175);
WIRE 16 -1 (350 2125)(600 2125);
WIRE 16 -1 (600 2175)(600 2125);
WIRE 16 -1 (350 2075)(600 2075);
WIRE 16 -1 (600 2125)(600 2075);
WIRE 16 -1 (350 2025)(600 2025);
WIRE 16 -1 (600 2075)(600 2025);
WIRE 16 -1 (350 1975)(600 1975);
WIRE 16 -1 (600 2025)(600 1975);
WIRE 16 -1 (350 1925)(600 1925);
WIRE 16 -1 (600 1975)(600 1925);
WIRE 16 -1 (350 1875)(600 1875);
WIRE 16 -1 (600 1875)(600 1925);
WIRE 16 -1 (350 1825)(600 1825);
WIRE 16 -1 (600 1875)(600 1825);
WIRE 16 -1 (350 1775)(600 1775);
WIRE 16 -1 (600 1825)(600 1775);
WIRE 16 -1 (350 1725)(600 1725);
WIRE 16 -1 (600 1775)(600 1725);
WIRE 16 -1 (350 1675)(600 1675);
WIRE 16 -1 (600 1675)(600 1725);
WIRE 16 -1 (350 1625)(600 1625);
WIRE 16 -1 (600 1675)(600 1625);
WIRE 16 -1 (600 1575)(350 1575);
WIRE 16 -1 (600 1625)(600 1575);
WIRE 16 -1 (600 1525)(350 1525);
WIRE 16 -1 (600 1575)(600 1525);
WIRE 16 -1 (600 1475)(350 1475);
WIRE 16 -1 (600 1525)(600 1475);
WIRE 16 -1 (600 1425)(350 1425);
WIRE 16 -1 (600 1475)(600 1425);
WIRE 16 -1 (350 1375)(600 1375);
WIRE 16 -1 (600 1375)(600 1425);
WIRE 16 -1 (600 1325)(350 1325);
WIRE 16 -1 (600 1325)(600 1375);
WIRE 16 -1 (600 1275)(350 1275);
WIRE 16 -1 (600 1325)(600 1275);
WIRE 16 -1 (600 1225)(350 1225);
WIRE 16 -1 (600 1275)(600 1225);
WIRE 16 -1 (350 1175)(600 1175);
WIRE 16 -1 (600 1225)(600 1175);
WIRE 16 -1 (350 1125)(600 1125);
WIRE 16 -1 (600 1175)(600 1125);
WIRE 16 -1 (350 1075)(600 1075);
WIRE 16 -1 (600 1125)(600 1075);
WIRE 16 -1 (350 1025)(600 1025);
WIRE 16 -1 (600 1075)(600 1025);
WIRE 16 -1 (350 975)(600 975);
WIRE 16 -1 (600 1025)(600 975);
WIRE 16 -1 (350 925)(600 925);
WIRE 16 -1 (600 975)(600 925);
WIRE 16 -1 (350 875)(600 875);
WIRE 16 -1 (600 925)(600 875);
WIRE 16 -1 (350 825)(600 825);
WIRE 16 -1 (600 825)(600 875);
WIRE 16 -1 (350 775)(600 775);
WIRE 16 -1 (600 825)(600 775);
WIRE 16 -1 (350 725)(600 725);
WIRE 16 -1 (600 775)(600 725);
WIRE 16 -1 (350 675)(600 675);
WIRE 16 -1 (600 725)(600 675);
WIRE 16 -1 (350 625)(600 625);
WIRE 16 -1 (600 625)(600 675);
WIRE 16 -1 (350 575)(600 575);
WIRE 16 -1 (600 625)(600 575);
WIRE 16 -1 (600 525)(350 525);
WIRE 16 -1 (600 575)(600 525);
WIRE 16 -1 (600 475)(350 475);
WIRE 16 -1 (600 525)(600 475);
WIRE 16 -1 (600 425)(350 425);
WIRE 16 -1 (600 475)(600 425);
WIRE 16 -1 (600 375)(350 375);
WIRE 16 -1 (600 425)(600 375);
WIRE 16 -1 (350 325)(600 325);
WIRE 16 -1 (600 325)(600 375);
WIRE 16 -1 (600 275)(350 275);
WIRE 16 -1 (600 275)(600 325);
WIRE 16 -1 (600 225)(350 225);
WIRE 16 -1 (600 275)(600 225);
WIRE 16 -1 (600 175)(350 175);
WIRE 16 -1 (600 225)(600 175);
WIRE 16 -1 (350 125)(600 125);
WIRE 16 -1 (600 175)(600 125);
WIRE 16 -1 (350 75)(600 75);
WIRE 16 -1 (600 125)(600 75);
WIRE 16 -1 (350 25)(600 25);
WIRE 16 -1 (600 75)(600 25);
WIRE 16 -1 (350 -25)(600 -25);
WIRE 16 -1 (600 25)(600 -25);
WIRE 16 -1 (350 -75)(600 -75);
WIRE 16 -1 (600 -25)(600 -75);
WIRE 16 -1 (350 -125)(600 -125);
WIRE 16 -1 (600 -75)(600 -125);
WIRE 16 -1 (350 -175)(600 -175);
WIRE 16 -1 (600 -125)(600 -175);
WIRE 16 -1 (600 -225)(600 -175);
WIRE 16 -1 (350 -225)(600 -225);
WIRE 16 -1 (-1200 3175)(-950 3175);
WIRE 16 -1 (-1200 3175)(-1200 3125);
WIRE 16 -1 (-1200 3125)(-950 3125);
WIRE 16 -1 (-1200 3125)(-1200 3075);
WIRE 16 -1 (-1200 3075)(-950 3075);
WIRE 16 -1 (-1200 3075)(-1200 3025);
WIRE 16 -1 (-1200 3025)(-950 3025);
WIRE 16 -1 (-1200 3025)(-1200 2975);
WIRE 16 -1 (-950 2975)(-1200 2975);
WIRE 16 -1 (-1200 2975)(-1200 2925);
WIRE 16 -1 (-1200 2925)(-950 2925);
WIRE 16 -1 (-1200 2925)(-1200 2875);
WIRE 16 -1 (-1200 2875)(-950 2875);
WIRE 16 -1 (-1200 2875)(-1200 2825);
WIRE 16 -1 (-1200 2825)(-950 2825);
WIRE 16 -1 (-1200 2825)(-1200 2775);
WIRE 16 -1 (-1200 2775)(-950 2775);
WIRE 16 -1 (-1200 2775)(-1200 2725);
WIRE 16 -1 (-950 2725)(-1200 2725);
WIRE 16 -1 (-1200 2725)(-1200 2675);
WIRE 16 -1 (-1200 2675)(-950 2675);
WIRE 16 -1 (-1200 2675)(-1200 2625);
WIRE 16 -1 (-1200 2625)(-950 2625);
WIRE 16 -1 (-1200 2625)(-1200 2575);
WIRE 16 -1 (-1200 2575)(-950 2575);
WIRE 16 -1 (-1200 2575)(-1200 2525);
WIRE 16 -1 (-1200 2525)(-950 2525);
WIRE 16 -1 (-1200 2525)(-1200 2475);
WIRE 16 -1 (-1200 2475)(-950 2475);
WIRE 16 -1 (-1200 2475)(-1200 2425);
WIRE 16 -1 (-950 2425)(-1200 2425);
WIRE 16 -1 (-1200 2425)(-1200 2375);
WIRE 16 -1 (-1200 2375)(-950 2375);
WIRE 16 -1 (-1200 2375)(-1200 2325);
WIRE 16 -1 (-1200 2325)(-950 2325);
WIRE 16 -1 (-1200 2325)(-1200 2275);
WIRE 16 -1 (-1200 2275)(-950 2275);
WIRE 16 -1 (-1200 2275)(-1200 2225);
WIRE 16 -1 (-1200 2225)(-950 2225);
WIRE 16 -1 (-1200 2225)(-1200 2175);
WIRE 16 -1 (-1200 2175)(-950 2175);
WIRE 16 -1 (-1200 2175)(-1200 2125);
WIRE 16 -1 (-1200 2125)(-950 2125);
WIRE 16 -1 (-1200 2125)(-1200 2075);
WIRE 16 -1 (-950 2075)(-1200 2075);
WIRE 16 -1 (-1200 2025)(-950 2025);
WIRE 16 -1 (-1200 2075)(-1200 2025);
WIRE 16 -1 (-1200 2025)(-1200 1975);
WIRE 16 -1 (-1200 1975)(-950 1975);
WIRE 16 -1 (-1200 1975)(-1200 1925);
WIRE 16 -1 (-1200 1925)(-950 1925);
WIRE 16 -1 (-1200 1925)(-1200 1875);
WIRE 16 -1 (-1200 1875)(-950 1875);
WIRE 16 -1 (-1200 1875)(-1200 1825);
WIRE 16 -1 (-1200 1825)(-950 1825);
WIRE 16 -1 (-1200 1825)(-1200 1775);
WIRE 16 -1 (-1200 1775)(-950 1775);
WIRE 16 -1 (-1200 1775)(-1200 1725);
WIRE 16 -1 (-1200 1725)(-950 1725);
WIRE 16 -1 (-1200 1725)(-1200 1675);
WIRE 16 -1 (-950 1675)(-1200 1675);
WIRE 16 -1 (-1200 1675)(-1200 1625);
WIRE 16 -1 (-1200 1625)(-950 1625);
WIRE 16 -1 (-1200 1625)(-1200 1575);
WIRE 16 -1 (-1200 1575)(-950 1575);
WIRE 16 -1 (-1200 1575)(-1200 1525);
WIRE 16 -1 (-1200 1525)(-950 1525);
WIRE 16 -1 (-1200 1525)(-1200 1475);
WIRE 16 -1 (-1200 1475)(-950 1475);
WIRE 16 -1 (-1200 1475)(-1200 1425);
WIRE 16 -1 (-1200 1425)(-950 1425);
WIRE 16 -1 (-1200 1425)(-1200 1375);
WIRE 16 -1 (-950 1375)(-1200 1375);
WIRE 16 -1 (-1200 1375)(-1200 1325);
WIRE 16 -1 (-1200 1325)(-950 1325);
WIRE 16 -1 (-1200 1325)(-1200 1275);
WIRE 16 -1 (-1200 1275)(-950 1275);
WIRE 16 -1 (-1200 1275)(-1200 1225);
WIRE 16 -1 (-1200 1225)(-950 1225);
WIRE 16 -1 (-1200 1225)(-1200 1175);
WIRE 16 -1 (-1200 1175)(-950 1175);
WIRE 16 -1 (-1200 1175)(-1200 1125);
WIRE 16 -1 (-1200 1125)(-950 1125);
WIRE 16 -1 (-1200 1125)(-1200 1075);
WIRE 16 -1 (-1200 1075)(-950 1075);
WIRE 16 -1 (-1200 1075)(-1200 1025);
WIRE 16 -1 (-950 1025)(-1200 1025);
WIRE 16 -1 (-1200 1025)(-1200 975);
WIRE 16 -1 (-1200 975)(-950 975);
WIRE 16 -1 (-1200 975)(-1200 925);
WIRE 16 -1 (-1200 925)(-950 925);
WIRE 16 -1 (-1200 925)(-1200 875);
WIRE 16 -1 (-1200 875)(-950 875);
WIRE 16 -1 (-1200 875)(-1200 825);
WIRE 16 -1 (-1200 825)(-950 825);
WIRE 16 -1 (-1200 825)(-1200 775);
WIRE 16 -1 (-1200 775)(-950 775);
WIRE 16 -1 (-1200 775)(-1200 725);
WIRE 16 -1 (-1200 725)(-950 725);
WIRE 16 -1 (-1200 725)(-1200 675);
WIRE 16 -1 (-1200 675)(-950 675);
WIRE 16 -1 (-1200 675)(-1200 625);
WIRE 16 -1 (-950 625)(-1200 625);
WIRE 16 -1 (-1200 625)(-1200 575);
WIRE 16 -1 (-1200 575)(-950 575);
WIRE 16 -1 (-1200 575)(-1200 525);
WIRE 16 -1 (-1200 525)(-950 525);
WIRE 16 -1 (-1200 525)(-1200 475);
WIRE 16 -1 (-1200 475)(-950 475);
WIRE 16 -1 (-1200 475)(-1200 425);
WIRE 16 -1 (-1200 425)(-950 425);
WIRE 16 -1 (-1200 425)(-1200 375);
WIRE 16 -1 (-1200 375)(-950 375);
WIRE 16 -1 (-1200 375)(-1200 325);
WIRE 16 -1 (-950 325)(-1200 325);
WIRE 16 -1 (-1200 325)(-1200 275);
WIRE 16 -1 (-1200 275)(-950 275);
WIRE 16 -1 (-1200 275)(-1200 225);
WIRE 16 -1 (-1200 225)(-950 225);
WIRE 16 -1 (-1200 225)(-1200 175);
WIRE 16 -1 (-1200 175)(-950 175);
WIRE 16 -1 (-1200 175)(-1200 125);
WIRE 16 -1 (-1200 125)(-950 125);
WIRE 16 -1 (-1200 125)(-1200 75);
WIRE 16 -1 (-1200 75)(-950 75);
WIRE 16 -1 (-1200 75)(-1200 25);
WIRE 16 -1 (-1200 25)(-950 25);
WIRE 16 -1 (-950 -25)(-1200 -25);
WIRE 16 -1 (-1200 25)(-1200 -25);
WIRE 16 -1 (-1200 -25)(-1200 -75);
WIRE 16 -1 (-1200 -75)(-950 -75);
WIRE 16 -1 (-1200 -75)(-1200 -125);
WIRE 16 -1 (-1200 -125)(-950 -125);
WIRE 16 -1 (-1200 -125)(-1200 -175);
WIRE 16 -1 (-1200 -175)(-950 -175);
WIRE 16 -1 (-1200 -175)(-1200 -225);
WIRE 16 -1 (-1200 -225)(-950 -225);
WIRE 16 -1 (4250 3175)(4500 3175);
WIRE 16 -1 (4250 3125)(4500 3125);
WIRE 16 -1 (4500 3175)(4500 3125);
WIRE 16 -1 (4250 3075)(4500 3075);
WIRE 16 -1 (4500 3125)(4500 3075);
WIRE 16 -1 (4250 3025)(4500 3025);
WIRE 16 -1 (4500 3025)(4500 3075);
WIRE 16 -1 (4250 2975)(4500 2975);
WIRE 16 -1 (4500 3025)(4500 2975);
WIRE 16 -1 (4500 2925)(4250 2925);
WIRE 16 -1 (4500 2975)(4500 2925);
WIRE 16 -1 (4250 2875)(4500 2875);
WIRE 16 -1 (4500 2925)(4500 2875);
WIRE 16 -1 (4250 2825)(4500 2825);
WIRE 16 -1 (4500 2875)(4500 2825);
WIRE 16 -1 (4250 2775)(4500 2775);
WIRE 16 -1 (4500 2825)(4500 2775);
WIRE 16 -1 (4250 2725)(4500 2725);
WIRE 16 -1 (4500 2725)(4500 2775);
WIRE 16 -1 (4250 2675)(4500 2675);
WIRE 16 -1 (4500 2725)(4500 2675);
WIRE 16 -1 (4500 2625)(4250 2625);
WIRE 16 -1 (4500 2675)(4500 2625);
WIRE 16 -1 (4500 2575)(4250 2575);
WIRE 16 -1 (4500 2625)(4500 2575);
WIRE 16 -1 (4500 2525)(4250 2525);
WIRE 16 -1 (4500 2575)(4500 2525);
WIRE 16 -1 (4500 2475)(4250 2475);
WIRE 16 -1 (4500 2525)(4500 2475);
WIRE 16 -1 (4250 2425)(4500 2425);
WIRE 16 -1 (4500 2425)(4500 2475);
WIRE 16 -1 (4500 2375)(4250 2375);
WIRE 16 -1 (4500 2375)(4500 2425);
WIRE 16 -1 (4500 2325)(4250 2325);
WIRE 16 -1 (4500 2375)(4500 2325);
WIRE 16 -1 (4500 2275)(4250 2275);
WIRE 16 -1 (4500 2325)(4500 2275);
WIRE 16 -1 (4250 2225)(4500 2225);
WIRE 16 -1 (4500 2275)(4500 2225);
WIRE 16 -1 (4250 2175)(4500 2175);
WIRE 16 -1 (4500 2225)(4500 2175);
WIRE 16 -1 (4250 2125)(4500 2125);
WIRE 16 -1 (4500 2175)(4500 2125);
WIRE 16 -1 (4250 2075)(4500 2075);
WIRE 16 -1 (4500 2125)(4500 2075);
WIRE 16 -1 (4250 2025)(4500 2025);
WIRE 16 -1 (4500 2075)(4500 2025);
WIRE 16 -1 (4250 1975)(4500 1975);
WIRE 16 -1 (4500 2025)(4500 1975);
WIRE 16 -1 (4250 1925)(4500 1925);
WIRE 16 -1 (4500 1975)(4500 1925);
WIRE 16 -1 (4250 1875)(4500 1875);
WIRE 16 -1 (4500 1875)(4500 1925);
WIRE 16 -1 (4250 1825)(4500 1825);
WIRE 16 -1 (4500 1875)(4500 1825);
WIRE 16 -1 (4250 1775)(4500 1775);
WIRE 16 -1 (4500 1825)(4500 1775);
WIRE 16 -1 (4250 1725)(4500 1725);
WIRE 16 -1 (4500 1775)(4500 1725);
WIRE 16 -1 (4250 1675)(4500 1675);
WIRE 16 -1 (4500 1675)(4500 1725);
WIRE 16 -1 (4250 1625)(4500 1625);
WIRE 16 -1 (4500 1675)(4500 1625);
WIRE 16 -1 (4500 1575)(4250 1575);
WIRE 16 -1 (4500 1625)(4500 1575);
WIRE 16 -1 (4500 1525)(4250 1525);
WIRE 16 -1 (4500 1575)(4500 1525);
WIRE 16 -1 (4500 1475)(4250 1475);
WIRE 16 -1 (4500 1525)(4500 1475);
WIRE 16 -1 (4500 1425)(4250 1425);
WIRE 16 -1 (4500 1475)(4500 1425);
WIRE 16 -1 (4250 1375)(4500 1375);
WIRE 16 -1 (4500 1375)(4500 1425);
WIRE 16 -1 (4500 1275)(4250 1275);
WIRE 16 -1 (4500 1275)(4500 1375);
WIRE 16 -1 (4500 1225)(4250 1225);
WIRE 16 -1 (4500 1275)(4500 1225);
WIRE 16 -1 (4250 1175)(4500 1175);
WIRE 16 -1 (4500 1225)(4500 1175);
WIRE 16 -1 (4250 1125)(4500 1125);
WIRE 16 -1 (4500 1175)(4500 1125);
WIRE 16 -1 (4250 1075)(4500 1075);
WIRE 16 -1 (4500 1125)(4500 1075);
WIRE 16 -1 (4250 1025)(4500 1025);
WIRE 16 -1 (4500 1075)(4500 1025);
WIRE 16 -1 (4250 975)(4500 975);
WIRE 16 -1 (4500 1025)(4500 975);
WIRE 16 -1 (4250 925)(4500 925);
WIRE 16 -1 (4500 975)(4500 925);
WIRE 16 -1 (4250 825)(4500 825);
WIRE 16 -1 (4500 825)(4500 925);
WIRE 16 -1 (4250 775)(4500 775);
WIRE 16 -1 (4500 825)(4500 775);
WIRE 16 -1 (4250 725)(4500 725);
WIRE 16 -1 (4500 775)(4500 725);
WIRE 16 -1 (4250 675)(4500 675);
WIRE 16 -1 (4500 725)(4500 675);
WIRE 16 -1 (4250 625)(4500 625);
WIRE 16 -1 (4500 625)(4500 675);
WIRE 16 -1 (4250 575)(4500 575);
WIRE 16 -1 (4500 625)(4500 575);
WIRE 16 -1 (4500 525)(4250 525);
WIRE 16 -1 (4500 575)(4500 525);
WIRE 16 -1 (4500 475)(4250 475);
WIRE 16 -1 (4500 525)(4500 475);
WIRE 16 -1 (4500 425)(4250 425);
WIRE 16 -1 (4500 475)(4500 425);
WIRE 16 -1 (4500 375)(4250 375);
WIRE 16 -1 (4500 425)(4500 375);
WIRE 16 -1 (4250 325)(4500 325);
WIRE 16 -1 (4500 325)(4500 375);
WIRE 16 -1 (4500 275)(4250 275);
WIRE 16 -1 (4500 275)(4500 325);
WIRE 16 -1 (4500 175)(4250 175);
WIRE 16 -1 (4500 175)(4500 275);
WIRE 16 -1 (4250 125)(4500 125);
WIRE 16 -1 (4500 175)(4500 125);
WIRE 16 -1 (4250 75)(4500 75);
WIRE 16 -1 (4500 125)(4500 75);
WIRE 16 -1 (4250 25)(4500 25);
WIRE 16 -1 (4500 75)(4500 25);
WIRE 16 -1 (4250 -25)(4500 -25);
WIRE 16 -1 (4500 25)(4500 -25);
WIRE 16 -1 (4250 -75)(4500 -75);
WIRE 16 -1 (4500 -25)(4500 -75);
WIRE 16 -1 (4500 -125)(4500 -75);
WIRE 16 -1 (4250 -125)(4500 -125);
DOT 1 (4500 25);
DOT 1 (2100 775);
DOT 1 (4500 475);
DOT 1 (2100 -125);
DOT 1 (2100 -75);
DOT 1 (2100 -25);
DOT 1 (4500 -75);
DOT 1 (4500 -25);
DOT 1 (2100 75);
DOT 1 (2100 125);
DOT 1 (2100 175);
DOT 1 (2100 225);
DOT 1 (2100 275);
DOT 1 (2100 325);
DOT 1 (2100 375);
DOT 1 (2100 425);
DOT 1 (2100 475);
DOT 1 (2100 525);
DOT 1 (2100 575);
DOT 1 (2100 625);
DOT 1 (2100 675);
DOT 1 (2100 725);
DOT 1 (2100 825);
DOT 1 (2100 875);
DOT 1 (2100 975);
DOT 1 (2100 925);
DOT 1 (2100 1025);
DOT 1 (2100 1075);
DOT 1 (2100 1125);
DOT 1 (2100 1175);
DOT 1 (2100 1225);
DOT 1 (2100 1275);
DOT 1 (2100 1375);
DOT 1 (2100 1325);
DOT 1 (2100 1425);
DOT 1 (2100 1475);
DOT 1 (2100 1525);
DOT 1 (2100 1625);
DOT 1 (2100 1575);
DOT 1 (2100 1675);
DOT 1 (2100 1725);
DOT 1 (2100 1775);
DOT 1 (2100 1875);
DOT 1 (2100 1825);
DOT 1 (2100 1925);
DOT 1 (2100 1975);
DOT 1 (2100 2025);
DOT 1 (2100 2075);
DOT 1 (2100 2125);
DOT 1 (2100 2175);
DOT 1 (2100 2225);
DOT 1 (2100 2275);
DOT 1 (2100 2325);
DOT 1 (2100 2375);
DOT 1 (2100 2425);
DOT 1 (2100 2475);
DOT 1 (2100 2525);
DOT 1 (2100 2575);
DOT 1 (2100 2625);
DOT 1 (2100 2675);
DOT 1 (2100 2725);
DOT 1 (2100 2775);
DOT 1 (2100 2825);
DOT 1 (2100 2875);
DOT 1 (2100 2925);
DOT 1 (2100 3025);
DOT 1 (2100 2975);
DOT 1 (2100 3075);
DOT 1 (2100 3125);
DOT 1 (4500 75);
DOT 1 (4500 125);
DOT 1 (4500 175);
DOT 1 (4500 275);
DOT 1 (4500 325);
DOT 1 (4500 375);
DOT 1 (4500 425);
DOT 1 (4500 525);
DOT 1 (4500 575);
DOT 1 (4500 725);
DOT 1 (4500 675);
DOT 1 (4500 775);
DOT 1 (4500 825);
DOT 1 (4500 975);
DOT 1 (4500 925);
DOT 1 (4500 1025);
DOT 1 (4500 1075);
DOT 1 (4500 1125);
DOT 1 (4500 1225);
DOT 1 (4500 1275);
DOT 1 (4500 1175);
DOT 1 (4500 1375);
DOT 1 (4500 1475);
DOT 1 (4500 1525);
DOT 1 (4500 1425);
DOT 1 (4500 1625);
DOT 1 (4500 1575);
DOT 1 (4500 1675);
DOT 1 (4500 1725);
DOT 1 (4500 1775);
DOT 1 (4500 1825);
DOT 1 (4500 1875);
DOT 1 (4500 1925);
DOT 1 (4500 1975);
DOT 1 (4500 2025);
DOT 1 (4500 2125);
DOT 1 (4500 2075);
DOT 1 (4500 2175);
DOT 1 (4500 2275);
DOT 1 (4500 2225);
DOT 1 (4500 2325);
DOT 1 (4500 2375);
DOT 1 (4500 2425);
DOT 1 (4500 2525);
DOT 1 (4500 2475);
DOT 1 (4500 2575);
DOT 1 (4500 2625);
DOT 1 (4500 2675);
DOT 1 (4500 2775);
DOT 1 (4500 2725);
DOT 1 (4500 2825);
DOT 1 (4500 2875);
DOT 1 (4500 2925);
DOT 1 (4500 3025);
DOT 1 (4500 2975);
DOT 1 (4500 3075);
DOT 1 (4500 3125);
DOT 1 (-1200 -275);
DOT 1 (-1200 -225);
DOT 1 (-1200 -175);
DOT 1 (-1200 -125);
DOT 1 (-1200 -75);
DOT 1 (-1200 -25);
DOT 1 (-1200 25);
DOT 1 (-1200 75);
DOT 1 (-1200 125);
DOT 1 (-1200 175);
DOT 1 (-1200 225);
DOT 1 (-1200 275);
DOT 1 (-1200 325);
DOT 1 (-1200 375);
DOT 1 (-1200 425);
DOT 1 (-1200 475);
DOT 1 (-1200 525);
DOT 1 (-1200 575);
DOT 1 (-1200 625);
DOT 1 (-1200 675);
DOT 1 (-1200 725);
DOT 1 (-1200 775);
DOT 1 (-1200 825);
DOT 1 (-1200 975);
DOT 1 (-1200 925);
DOT 1 (-1200 1025);
DOT 1 (-1200 1075);
DOT 1 (-1200 1125);
DOT 1 (-1200 1175);
DOT 1 (-1200 1225);
DOT 1 (-1200 1275);
DOT 1 (-1200 1375);
DOT 1 (-1200 1425);
DOT 1 (-1200 1475);
DOT 1 (-1200 1525);
DOT 1 (-1200 1625);
DOT 1 (-1200 1575);
DOT 1 (-1200 1875);
DOT 1 (-1200 1925);
DOT 1 (-1200 1975);
DOT 1 (-1200 2025);
DOT 1 (-1200 2075);
DOT 1 (-1200 2125);
DOT 1 (-1200 2175);
DOT 1 (-1200 2225);
DOT 1 (-1200 2275);
DOT 1 (-1200 2325);
DOT 1 (-1200 2375);
DOT 1 (-1200 2425);
DOT 1 (-1200 2525);
DOT 1 (-1200 2575);
DOT 1 (-1200 2775);
DOT 1 (-1200 2825);
DOT 1 (-1200 2875);
DOT 1 (-1200 2925);
DOT 1 (-1200 3025);
DOT 1 (-1200 2975);
DOT 1 (-1200 3075);
DOT 1 (-1200 3125);
DOT 1 (-1200 1325);
DOT 1 (-1200 2725);
DOT 1 (-1200 2675);
DOT 1 (-1200 2625);
DOT 1 (-1200 2475);
DOT 1 (600 3125);
DOT 1 (600 3075);
DOT 1 (600 3025);
DOT 1 (600 2975);
DOT 1 (600 2875);
DOT 1 (600 2925);
DOT 1 (600 2775);
DOT 1 (600 2825);
DOT 1 (600 2725);
DOT 1 (600 2625);
DOT 1 (600 2675);
DOT 1 (600 2575);
DOT 1 (600 2525);
DOT 1 (600 2475);
DOT 1 (600 2375);
DOT 1 (600 2425);
DOT 1 (600 2275);
DOT 1 (600 2225);
DOT 1 (600 2325);
DOT 1 (600 2125);
DOT 1 (600 2175);
DOT 1 (600 2075);
DOT 1 (600 2025);
DOT 1 (600 1975);
DOT 1 (600 1875);
DOT 1 (600 1925);
DOT 1 (600 1825);
DOT 1 (600 1725);
DOT 1 (600 1775);
DOT 1 (600 1675);
DOT 1 (600 1625);
DOT 1 (600 1575);
DOT 1 (600 1525);
DOT 1 (600 1475);
DOT 1 (600 1375);
DOT 1 (600 1425);
DOT 1 (600 1325);
DOT 1 (600 1225);
DOT 1 (600 1275);
DOT 1 (600 1075);
DOT 1 (600 1125);
DOT 1 (600 1175);
DOT 1 (600 1025);
DOT 1 (600 975);
DOT 1 (600 925);
DOT 1 (600 825);
DOT 1 (600 875);
DOT 1 (600 725);
DOT 1 (600 775);
DOT 1 (600 675);
DOT 1 (600 575);
DOT 1 (600 625);
DOT 1 (600 525);
DOT 1 (600 425);
DOT 1 (600 375);
DOT 1 (600 325);
DOT 1 (600 225);
DOT 1 (600 175);
DOT 1 (600 275);
DOT 1 (600 75);
DOT 1 (600 125);
DOT 1 (600 25);
DOT 1 (600 -25);
DOT 1 (600 -75);
DOT 1 (600 -125);
DOT 1 (600 -175);
DOT 1 (600 -225);
DOT 1 (600 -275);
DOT 1 (4500 625);
DOT 1 (-1200 875);
DOT 1 (4500 -125);
DOT 1 (4500 -175);
DOT 1 (2100 25);
DOT 1 (-1200 1675);
DOT 1 (-1200 1725);
DOT 1 (-1200 1775);
DOT 1 (-1200 1825);
DOT 1 (600 475);
QUIT
